(kicad_pcb
	(version 20260206)
	(generator "pcbnew")
	(generator_version "10.0")
	(general
		(thickness 1.6)
		(legacy_teardrops no)
	)
	(paper "A4")
	(title_block
		(title "v2-pdb — ms_pdb_v2.brd")
		(comment 1 "Open CloudServer (Microsoft) / footprints 329-329 of 348")
	)
	(layers
		(0 "F.Cu" signal "TOP")
		(4 "In1.Cu" signal "GND")
		(6 "In2.Cu" signal "IN1")
		(8 "In3.Cu" signal "VCC")
		(10 "In4.Cu" signal "VCC1")
		(12 "In5.Cu" signal "IN2")
		(14 "In6.Cu" signal "GND1")
		(2 "B.Cu" signal "BOTTOM")
		(9 "F.Adhes" user "F.Adhesive")
		(11 "B.Adhes" user "B.Adhesive")
		(13 "F.Paste" user "Package Geometry/Pastemask Top")
		(15 "B.Paste" user "Package Geometry/Pastemask Bottom")
		(5 "F.SilkS" user "Ref Des/Silkscreen Top")
		(7 "B.SilkS" user "Ref Des/Silkscreen Bottom")
		(1 "F.Mask" user "Board Geometry/Soldermask Top")
		(3 "B.Mask" user "Board Geometry/Soldermask Bottom")
		(17 "Dwgs.User" user "User.Drawings")
		(19 "Cmts.User" user "User.Comments")
		(21 "Eco1.User" user "User.Eco1")
		(23 "Eco2.User" user "User.Eco2")
		(25 "Edge.Cuts" user "Board Geometry/Outline")
		(27 "Margin" user)
		(31 "F.CrtYd" user "Package Geometry/Place Bound Top")
		(29 "B.CrtYd" user "Package Geometry/Place Bound Bottom")
		(35 "F.Fab" user "Ref Des/Assembly Top")
		(33 "B.Fab" user "Ref Des/Assembly Bottom")
	)
	(footprint ""
		(layer "B.Cu")
		(at 96.468946 -345.12377)
		(property "Reference" "U6"
			(at 4.374134 -0.517906 0)
			(unlocked yes)
			(layer "B.SilkS")
			(effects
				(font
					(size 0.7874 0.5842)
					(thickness 0.1524)
				)
				(justify left mirror)
			)
		)
		(property "Value" ""
			(at 0 0 0)
			(layer "B.Fab")
			(effects
				(font
					(size 1.27 1.27)
				)
				(justify mirror)
			)
		)
		(duplicate_pad_numbers_are_jumpers no)
		(fp_line
			(start -2.5527 -2.0066)
			(end -2.5527 2.0066)
			(stroke
				(width 0.1524)
				(type default)
			)
			(layer "B.SilkS")
		)
		(fp_line
			(start -2.5527 2.0066)
			(end 2.5527 2.0066)
			(stroke
				(width 0.1524)
				(type default)
			)
			(layer "B.SilkS")
		)
		(fp_line
			(start 1.9812 0)
			(end 2.5527 -0.5715)
			(stroke
				(width 0.1524)
				(type default)
			)
			(layer "B.SilkS")
		)
		(fp_line
			(start 2.5527 -2.0066)
			(end -2.5527 -2.0066)
			(stroke
				(width 0.1524)
				(type default)
			)
			(layer "B.SilkS")
		)
		(fp_line
			(start 2.5527 -0.5715)
			(end 2.5527 -2.0066)
			(stroke
				(width 0.1524)
				(type default)
			)
			(layer "B.SilkS")
		)
		(fp_line
			(start 2.5527 0.5715)
			(end 1.9812 0)
			(stroke
				(width 0.1524)
				(type default)
			)
			(layer "B.SilkS")
		)
		(fp_line
			(start 2.5527 2.0066)
			(end 2.5527 0.5715)
			(stroke
				(width 0.1524)
				(type default)
			)
			(layer "B.SilkS")
		)
		(fp_circle
			(center 2.032 1.524)
			(end 2.286 1.524)
			(stroke
				(width 0.1524)
				(type default)
			)
			(fill no)
			(layer "B.SilkS")
		)
		(fp_rect
			(start 2.5527 3.6703)
			(end -2.5527 -3.6703)
			(stroke
				(width 0)
				(type default)
			)
			(fill no)
			(layer "B.CrtYd")
		)
		(fp_line
			(start -2.549906 -2.249932)
			(end -2.549906 2.249932)
			(stroke
				(width 0.1)
				(type default)
			)
			(layer "B.Fab")
		)
		(fp_line
			(start -2.549906 2.249932)
			(end 2.549906 2.249932)
			(stroke
				(width 0.1)
				(type default)
			)
			(layer "B.Fab")
		)
		(fp_line
			(start 2.549906 -2.249932)
			(end -2.549906 -2.249932)
			(stroke
				(width 0.1)
				(type default)
			)
			(layer "B.Fab")
		)
		(fp_line
			(start 2.549906 2.249932)
			(end 2.549906 -2.249932)
			(stroke
				(width 0.1)
				(type default)
			)
			(layer "B.Fab")
		)
		(pad "1" smd rect
			(at 1.949958 2.921 180)
			(size 0.3556 1.4986)
			(layers "B.Cu" "B.Mask" "B.Paste")
			(net "PSU_ALERT_N")
		)
		(pad "2" smd rect
			(at 1.299972 2.921 180)
			(size 0.3556 1.4986)
			(layers "B.Cu" "B.Mask" "B.Paste")
			(net "B13_PSU_ALERT_N")
		)
		(pad "3" smd rect
			(at 0.649986 2.921 180)
			(size 0.3556 1.4986)
			(layers "B.Cu" "B.Mask" "B.Paste")
			(net "PSU_ALERT_N")
		)
		(pad "4" smd rect
			(at 0 2.921 180)
			(size 0.3556 1.4986)
			(layers "B.Cu" "B.Mask" "B.Paste")
			(net "B14_PSU_ALERT_N")
		)
		(pad "5" smd rect
			(at -0.649986 2.921 180)
			(size 0.3556 1.4986)
			(layers "B.Cu" "B.Mask" "B.Paste")
			(net "PSU_ALERT_N")
		)
		(pad "6" smd rect
			(at -1.299972 2.921 180)
			(size 0.3556 1.4986)
			(layers "B.Cu" "B.Mask" "B.Paste")
			(net "B15_PSU_ALERT_N")
		)
		(pad "7" smd rect
			(at -1.949958 2.921 180)
			(size 0.3556 1.4986)
			(layers "B.Cu" "B.Mask" "B.Paste")
			(net "GND")
		)
		(pad "8" smd rect
			(at -1.949958 -2.921 180)
			(size 0.3556 1.4986)
			(layers "B.Cu" "B.Mask" "B.Paste")
			(net "B16_PSU_ALERT_N")
		)
		(pad "9" smd rect
			(at -1.299972 -2.921 180)
			(size 0.3556 1.4986)
			(layers "B.Cu" "B.Mask" "B.Paste")
			(net "PSU_ALERT_N")
		)
		(pad "10" smd rect
			(at -0.649986 -2.921 180)
			(size 0.3556 1.4986)
			(layers "B.Cu" "B.Mask" "B.Paste")
			(net "B17_PSU_ALERT_N")
		)
		(pad "11" smd rect
			(at 0 -2.921 180)
			(size 0.3556 1.4986)
			(layers "B.Cu" "B.Mask" "B.Paste")
			(net "PSU_ALERT_N")
		)
		(pad "12" smd rect
			(at 0.649986 -2.921 180)
			(size 0.3556 1.4986)
			(layers "B.Cu" "B.Mask" "B.Paste")
			(net "B18_PSU_ALERT_N")
		)
		(pad "13" smd rect
			(at 1.299972 -2.921 180)
			(size 0.3556 1.4986)
			(layers "B.Cu" "B.Mask" "B.Paste")
			(net "PSU_ALERT_N")
		)
		(pad "14" smd rect
			(at 1.949958 -2.921 180)
			(size 0.3556 1.4986)
			(layers "B.Cu" "B.Mask" "B.Paste")
			(net "P3V3_BUF")
		)
	)
)
